# T6G (Grand Teton) — schematic parts with pin connectivity, parts 3663–3803 of 8303; source: Cadence DE-HDL packaged netlist (pstxprt.dat, pstxnet.dat, pstchip.dat)

PC6562  Q_CAP  0.1UF 25V 10% X7R  pkg 0402  page 363 : 1 = P12V_AUX ; 2 = GND
PC6563  Q_CAP  100NF 50V 10% X7R  pkg C0402  page 363 : 1 = SW_P0V9_RETIMER_CPU0_BOOT1_RC ; 2 = SW_P0V9_RETIMER_CPU0_PH1
PC6564  Q_CAP  560PF 50V 10% EMPTY  pkg C0402  page 363 : 1 = SW_P0V9_RETIMER_CPU0_SW1 ; 2 = SW_P0V9_RETIMER_CPU0_SW1_RC
PC6565  Q_CAP  100NF 50V 10% X7R  pkg C0402  page 363 : 1 = P0V9_CPU0_RT_2D ; 2 = GND
PC6566_1  Q_CAP  22UF 4V 20% X6S  pkg C0805  page 363 : 1 = P0V9_CPU0_RT_2D ; 2 = GND
PC6567_1  Q_CAP  22UF 4V 20% X6S  pkg C0805  page 363 : 1 = P0V9_CPU0_RT_2D ; 2 = GND
PC6568  Q_CAPP  470UF 2.5V 20% SPCAP  pkg SMLF  page 363 : 1 = P0V9_CPU0_RT_2D ; 2 = GND
PC6569  Q_CAPP  470UF 2.5V 20% SPCAP  pkg SMLF  page 363 : 1 = P0V9_CPU0_RT_2D ; 2 = GND
PC6570  Q_CAPP  470UF 2.5V 20% SPCAP  pkg SMLF  page 363 : 1 = P0V9_CPU0_RT_2D ; 2 = GND
PC6571  Q_CAPP  390UF 2.5V 20% ALUM  pkg SMLF  page 363 : 1 = P0V9_CPU0_RT_2D ; 2 = GND
PC6572  Q_CAPP  390UF 2.5V 20% ALUM  pkg SMLF  page 363 : 1 = P0V9_CPU0_RT_2D ; 2 = GND
PC6573  Q_CAPP  390UF 2.5V 20% ALUM  pkg SMLF  page 363 : 1 = P0V9_CPU0_RT_2D ; 2 = GND
PC6574  Q_CAPP  390UF 2.5V 20% ALUM  pkg SMLF  page 363 : 1 = P0V9_CPU0_RT_2D ; 2 = GND
PC6575  Q_CAP  2.2UF 10V 10% X6S  pkg C0402  page 363 : 1 = P0V9_RETIMER_CPU0_VCC2 ; 2 = GND
PC6576  Q_CAP  100NF 50V 10% X7R  pkg C0402  page 363 : 1 = PV09_RETIMER_CPU0_VCCS ; 2 = GND
PC6577_2  Q_CAP  1UF 25V 10% X6S  pkg C0402  page 363 : 1 = SW_P12V_AUX_P0V9_RETIMER_CPU0_FLT ; 2 = GND
PC6578_2  Q_CAP  3300PF 50V 10% X7R  pkg 0402  page 363 : 1 = SW_P12V_AUX_P0V9_RETIMER_CPU0_FLT ; 2 = GND
PC6579_2  Q_CAP  22UF 16V 20% X6S  pkg C0805  page 363 : 1 = SW_P12V_AUX_P0V9_RETIMER_CPU0_FLT ; 2 = GND
PC6580_2  Q_CAP  22UF 16V 20% X6S  pkg C0805  page 363 : 1 = SW_P12V_AUX_P0V9_RETIMER_CPU0_FLT ; 2 = GND
PC6581_2  Q_CAP  22UF 16V 20% X6S  pkg C0805  page 363 : 1 = SW_P12V_AUX_P0V9_RETIMER_CPU0_FLT ; 2 = GND
PC6582_2  Q_CAP  22UF 16V 20% X6S  pkg C0805  page 363 : 1 = SW_P12V_AUX_P0V9_RETIMER_CPU0_FLT ; 2 = GND
PC6583  Q_CAP  22UF 16V 20% X6S  pkg C0805  page 363 : 1 = SW_P12V_AUX_P0V9_RETIMER_CPU0_FLT ; 2 = GND
PC6584  Q_CAP  100NF 50V 10% X7R  pkg C0402  page 363 : 1 = SW_P0V9_RETIMER_CPU0_BOOT2_RC ; 2 = SW_P0V9_RETIMER_CPU0_PH2
PC6585  Q_CAP  560PF 50V 10% EMPTY  pkg C0402  page 363 : 1 = SW_P0V9_RETIMER_CPU0_SW2 ; 2 = SW_P0V9_RETIMER_CPU0_SW2_RC
PC6586_2  Q_CAP  22UF 4V 20% X6S  pkg C0805  page 363 : 1 = P0V9_CPU0_RT_2D ; 2 = GND
PC6587_2  Q_CAP  22UF 4V 20% X6S  pkg C0805  page 363 : 1 = P0V9_CPU0_RT_2D ; 2 = GND
PC6600  Q_CAP  3300PF 50V 10% X7R  pkg 0402  page 364 : 1 = P0V9_RETIMER_CPU1_SENSE_R_P ; 2 = P0V9_RETIMER_CPU1_SENSE_SH_N
PC6601  Q_CAP  0.1UF 25V 10% EMPTY  pkg 0402  page 362 : 1 = P0V9_RETIMER_CPU0_VMON ; 2 = GND
PC6602  Q_CAP  0.1UF 25V 10% X7R  pkg 0402  page 362 : 1 = P0V9_RETIMER_CPU0_VINSEN ; 2 = GND
PC6603  Q_CAP  100NF 50V 10% X7R  pkg C0402  page 362 : 1 = P0V9_RETIMER_CPU0_VCC ; 2 = GND
PC6604  Q_CAP  1UF 16V 10% X6S  pkg C0402  page 362 : 1 = P0V9_RETIMER_CPU0_VCC ; 2 = GND
PC6605  Q_CAP  1UF 16V 10% X6S  pkg C0402  page 362 : 1 = PV09_RETIMER_CPU0_VCCS ; 2 = GND
PC6606  Q_CAP  10UF 6.3V 20% X6S  pkg C0402  page 362 : 1 = PV09_RETIMER_CPU0_VCCS ; 2 = GND
PC6607  Q_CAP  470PF 50V 10% X7R  pkg 0402  page 362 : 1 = P0V9_RETIMER_CPU0_TEMP0 ; 2 = GND
PC6609_09P1_1  Q_CAP  2.2UF 10V 10% X6S  pkg C0402  page 365 : 1 = P0V9_RETIMER_CPU1_PVCC ; 2 = GND
PC6610  Q_CAP  2.2UF 10V 10% X6S  pkg C0402  page 365 : 1 = P0V9_RETIMER_CPU1_VCC1 ; 2 = GND
PC6611_1  Q_CAP  100NF 50V 10% X7R  pkg C0402  page 365 : 1 = PV09_RETIMER_CPU1_VCCS ; 2 = GND
PC6612_1  Q_CAP  1UF 25V 10% X6S  pkg C0402  page 365 : 1 = SW_P12V_AUX_P0V9_RETIMER_CPU1_FLT ; 2 = GND
PC6613_1  Q_CAP  3300PF 50V 10% X7R  pkg 0402  page 365 : 1 = SW_P12V_AUX_P0V9_RETIMER_CPU1_FLT ; 2 = GND
PC6614_1  Q_CAP  22UF 16V 20% X6S  pkg C0805  page 365 : 1 = SW_P12V_AUX_P0V9_RETIMER_CPU1_FLT ; 2 = GND
PC6615_1  Q_CAP  22UF 16V 20% X6S  pkg C0805  page 365 : 1 = SW_P12V_AUX_P0V9_RETIMER_CPU1_FLT ; 2 = GND
PC6616_1  Q_CAP  22UF 16V 20% X6S  pkg C0805  page 365 : 1 = SW_P12V_AUX_P0V9_RETIMER_CPU1_FLT ; 2 = GND
PC6617_1  Q_CAP  22UF 16V 20% X6S  pkg C0805  page 365 : 1 = SW_P12V_AUX_P0V9_RETIMER_CPU1_FLT ; 2 = GND
PC6618  Q_CAP  22UF 16V 20% X6S  pkg C0805  page 365 : 1 = SW_P12V_AUX_P0V9_RETIMER_CPU1_FLT ; 2 = GND
PC6619  Q_CAPP  100UF 16V 20% OSCON  pkg SMLF  page 365 : 1 = SW_P12V_AUX_P0V9_RETIMER_CPU1_FLT ; 2 = GND
PC6620  Q_CAP  0.1UF 25V 10% X7R  pkg 0402  page 365 : 1 = P12V_AUX ; 2 = GND
PC6621  Q_CAP  100NF 50V 10% X7R  pkg C0402  page 365 : 1 = SW_P0V9_RETIMER_CPU1_BOOT1_RC ; 2 = SW_P0V9_RETIMER_CPU1_PH1
PC6622  Q_CAP  560PF 50V 10% EMPTY  pkg C0402  page 365 : 1 = SW_P0V9_RETIMER_CPU1_SW1 ; 2 = SW_P0V9_RETIMER_CPU1_SW1_RC
PC6623  Q_CAP  100NF 50V 10% X7R  pkg C0402  page 365 : 1 = P0V9_CPU1_RT_2D ; 2 = GND
PC6624_1  Q_CAP  22UF 4V 20% X6S  pkg C0805  page 365 : 1 = P0V9_CPU1_RT_2D ; 2 = GND
PC6625_1  Q_CAP  22UF 4V 20% X6S  pkg C0805  page 365 : 1 = P0V9_CPU1_RT_2D ; 2 = GND
PC6626  Q_CAPP  470UF 2.5V 20% SPCAP  pkg SMLF  page 365 : 1 = P0V9_CPU1_RT_2D ; 2 = GND
PC6627  Q_CAPP  470UF 2.5V 20% SPCAP  pkg SMLF  page 365 : 1 = P0V9_CPU1_RT_2D ; 2 = GND
PC6628  Q_CAPP  470UF 2.5V 20% SPCAP  pkg SMLF  page 365 : 1 = P0V9_CPU1_RT_2D ; 2 = GND
PC6629  Q_CAPP  390UF 2.5V 20% ALUM  pkg SMLF  page 365 : 1 = P0V9_CPU1_RT_2D ; 2 = GND
PC6630  Q_CAPP  390UF 2.5V 20% ALUM  pkg SMLF  page 365 : 1 = P0V9_CPU1_RT_2D ; 2 = GND
PC6631  Q_CAPP  390UF 2.5V 20% ALUM  pkg SMLF  page 365 : 1 = P0V9_CPU1_RT_2D ; 2 = GND
PC6632  Q_CAPP  390UF 2.5V 20% ALUM  pkg SMLF  page 365 : 1 = P0V9_CPU1_RT_2D ; 2 = GND
PC6633_2  Q_CAP  1UF 25V 10% X6S  pkg C0402  page 365 : 1 = SW_P12V_AUX_P0V9_RETIMER_CPU1_FLT ; 2 = GND
PC6634_2  Q_CAP  3300PF 50V 10% X7R  pkg 0402  page 365 : 1 = SW_P12V_AUX_P0V9_RETIMER_CPU1_FLT ; 2 = GND
PC6635_2  Q_CAP  22UF 16V 20% X6S  pkg C0805  page 365 : 1 = SW_P12V_AUX_P0V9_RETIMER_CPU1_FLT ; 2 = GND
PC6636_2  Q_CAP  22UF 16V 20% X6S  pkg C0805  page 365 : 1 = SW_P12V_AUX_P0V9_RETIMER_CPU1_FLT ; 2 = GND
PC6637_2  Q_CAP  22UF 16V 20% X6S  pkg C0805  page 365 : 1 = SW_P12V_AUX_P0V9_RETIMER_CPU1_FLT ; 2 = GND
PC6638_2  Q_CAP  22UF 16V 20% X6S  pkg C0805  page 365 : 1 = SW_P12V_AUX_P0V9_RETIMER_CPU1_FLT ; 2 = GND
PC6639  Q_CAP  22UF 16V 20% X6S  pkg C0805  page 365 : 1 = SW_P12V_AUX_P0V9_RETIMER_CPU1_FLT ; 2 = GND
PC6640  Q_CAP  100NF 50V 10% X7R  pkg C0402  page 365 : 1 = SW_P0V9_RETIMER_CPU1_BOOT2_RC ; 2 = SW_P0V9_RETIMER_CPU1_PH2
PC6641  Q_CAP  560PF 50V 10% EMPTY  pkg C0402  page 365 : 1 = SW_P0V9_RETIMER_CPU1_SW2 ; 2 = SW_P0V9_RETIMER_CPU1_SW2_RC
PC6642_2  Q_CAP  22UF 4V 20% X6S  pkg C0805  page 365 : 1 = P0V9_CPU1_RT_2D ; 2 = GND
PC6643_2  Q_CAP  22UF 4V 20% X6S  pkg C0805  page 365 : 1 = P0V9_CPU1_RT_2D ; 2 = GND
PC6644_09P1_2  Q_CAP  2.2UF 10V 10% X6S  pkg C0402  page 365 : 1 = P0V9_RETIMER_CPU1_PVCC ; 2 = GND
PC6645  Q_CAP  2.2UF 10V 10% X6S  pkg C0402  page 365 : 1 = P0V9_RETIMER_CPU1_VCC2 ; 2 = GND
PC6646  Q_CAP  100NF 50V 10% X7R  pkg C0402  page 365 : 1 = PV09_RETIMER_CPU1_VCCS ; 2 = GND
PC6800  Q_CAPP  270UF 16V 20% OSCON  pkg SMLF  page 360 : 1 = SW_P12V_AUX_P1V8_RETIMER_CPU0_FLT ; 2 = GND
PC6801  Q_CAPP  270UF 16V 20% OSCON  pkg SMLF  page 361 : 1 = SW_P12V_AUX_P1V8_RETIMER_CPU1_FLT ; 2 = GND
PC6802  Q_CAP  22UF 16V 20% X6S  pkg C0805  page 360 : 1 = SW_P12V_AUX_P1V8_RETIMER_CPU0_FLT ; 2 = GND
PC6803  Q_CAP  22UF 16V 20% X6S  pkg C0805  page 361 : 1 = SW_P12V_AUX_P1V8_RETIMER_CPU1_FLT ; 2 = GND
PC6804  Q_CAPP  390UF 2.5V 20% ALUM  pkg SMLF  page 361 : 1 = P1V8_CPU1_RT_1D ; 2 = GND
PC6805  Q_CAPP  390UF 2.5V 20% ALUM  pkg SMLF  page 360 : 1 = P1V8_CPU0_RT_1D ; 2 = GND
PC6806  Q_CAP  100NF 50V 10% X7R  pkg C0402  page 363 : 1 = P0V9_CPU0_RT_2D ; 2 = GND
PC6807  Q_CAP  100NF 50V 10% X7R  pkg C0402  page 365 : 1 = P0V9_CPU1_RT_2D ; 2 = GND
PC6810  Q_CAPP  100UF 16V 20% OSCON  pkg SMLF  page 363 : 1 = SW_P12V_AUX_P0V9_RETIMER_CPU0_FLT ; 2 = GND
PC6811  Q_CAPP  470UF 2.5V 20% SPCAP  pkg SMLF  page 363 : 1 = P0V9_CPU0_RT_2D ; 2 = GND
PC6812  Q_CAPP  470UF 2.5V 20% SPCAP  pkg SMLF  page 363 : 1 = P0V9_CPU0_RT_2D ; 2 = GND
PC6813  Q_CAPP  470UF 2.5V 20% SPCAP  pkg SMLF  page 365 : 1 = P0V9_CPU1_RT_2D ; 2 = GND
PC6814  Q_CAPP  470UF 2.5V 20% SPCAP  pkg SMLF  page 365 : 1 = P0V9_CPU1_RT_2D ; 2 = GND
PC6815  Q_CAPP  470UF 2.5V 20% SPCAP  pkg SMLF  page 365 : 1 = P0V9_CPU1_RT_2D ; 2 = GND
PC6816  Q_CAP  22UF 16V 20% X6S  pkg C0805  page 363 : 1 = SW_P12V_AUX_P0V9_RETIMER_CPU0_FLT ; 2 = GND
PC6817  Q_CAP  22UF 16V 20% X6S  pkg C0805  page 363 : 1 = SW_P12V_AUX_P0V9_RETIMER_CPU0_FLT ; 2 = GND
PC6818  Q_CAP  22UF 16V 20% X6S  pkg C0805  page 365 : 1 = SW_P12V_AUX_P0V9_RETIMER_CPU1_FLT ; 2 = GND
PC6819  Q_CAP  22UF 16V 20% X6S  pkg C0805  page 365 : 1 = SW_P12V_AUX_P0V9_RETIMER_CPU1_FLT ; 2 = GND
PC6900  Q_CAP  22UF 16V 20% X6S  pkg C0805  page 360 : 1 = SW_P12V_AUX_P1V8_RETIMER_CPU0_FLT ; 2 = GND
PC6901  Q_CAP  22UF 16V 20% X6S  pkg C0805  page 360 : 1 = SW_P12V_AUX_P1V8_RETIMER_CPU0_FLT ; 2 = GND
PC6902  Q_CAP  22UF 16V 20% X6S  pkg C0805  page 360 : 1 = SW_P12V_AUX_P1V8_RETIMER_CPU0_FLT ; 2 = GND
PC6903  Q_CAP  22UF 16V 20% X6S  pkg C0805  page 361 : 1 = SW_P12V_AUX_P1V8_RETIMER_CPU1_FLT ; 2 = GND
PC6904  Q_CAP  22UF 16V 20% X6S  pkg C0805  page 361 : 1 = SW_P12V_AUX_P1V8_RETIMER_CPU1_FLT ; 2 = GND
PC6905  Q_CAP  22UF 16V 20% X6S  pkg C0805  page 361 : 1 = SW_P12V_AUX_P1V8_RETIMER_CPU1_FLT ; 2 = GND
PC7000  Q_CAP  22UF 16V 20% X6S  pkg C0805  page 205 : 1 = SW_P12V_AUX_PVDDIO_P0_FLT ; 2 = GND
PC7001  Q_CAP  22UF 16V 20% X6S  pkg C0805  page 222 : 1 = SW_P12V_AUX_PVDDIO_P1_FLT ; 2 = GND
PC7002  Q_CAP  22UF 16V 20% X6S  pkg C0805  page 208 : 1 = SW_P12V_AUX_PVDD11_S3_P0_FLT ; 2 = GND
PC7003  Q_CAP  22UF 16V 20% X6S  pkg C0805  page 225 : 1 = SW_P12V_AUX_PVDD11_S3_P1_FLT ; 2 = GND
PC8000  Q_CAP  22UF 16V 20% X6S  pkg C0805  page 192 : 1 = SW_P12V_AUX_PVDD_33_S5_FLT ; 2 = GND
PC8001  Q_CAP  22UF 16V 20% X6S  pkg C0805  page 192 : 1 = SW_P12V_AUX_PVDD_33_S5_FLT ; 2 = GND
PC8002  Q_CAP  22UF 16V 20% X6S  pkg C0805  page 209 : 1 = SW_P12V_AUX_PVDD18_S5_P0_FLT ; 2 = GND
PC8003  Q_CAP  22UF 16V 20% X6S  pkg C0805  page 226 : 1 = SW_P12V_AUX_PVDD18_S5_P1_FLT ; 2 = GND
PC8004  Q_CAP  22UF 16V 20% X6S  pkg C0805  page 208 : 1 = SW_P12V_AUX_PVDD11_S3_P0_FLT ; 2 = GND
PC8005  Q_CAP  22UF 16V 20% X6S  pkg C0805  page 208 : 1 = SW_P12V_AUX_PVDD11_S3_P0_FLT ; 2 = GND
PC8006  Q_CAP  22UF 16V 20% X6S  pkg C0805  page 225 : 1 = SW_P12V_AUX_PVDD11_S3_P1_FLT ; 2 = GND
PC8007  Q_CAP  22UF 16V 20% X6S  pkg C0805  page 225 : 1 = SW_P12V_AUX_PVDD11_S3_P1_FLT ; 2 = GND
PC8008  Q_CAP  1UF 16V 10% X7R  pkg 0603  page 190 : 1 = P12V_AUX ; 2 = GND
PC8009  Q_CAP  22UF 16V 20% X6S  pkg C0805  page 198 : 1 = SW_P12V_AUX_PVDDCR_SOC_P0_FLT ; 2 = GND
PC8010  Q_CAP  22UF 16V 20% X6S  pkg C0805  page 198 : 1 = SW_P12V_AUX_PVDDCR_SOC_P0_FLT ; 2 = GND
PC8011  Q_CAP  22UF 16V 20% X6S  pkg C0805  page 215 : 1 = SW_P12V_AUX_PVDDCR_SOC_P1_FLT ; 2 = GND
PC8012  Q_CAP  22UF 16V 20% X6S  pkg C0805  page 215 : 1 = SW_P12V_AUX_PVDDCR_SOC_P1_FLT ; 2 = GND
PC8013  Q_CAP  22UF 16V 20% X6S  pkg C0805  page 190 : 1 = SW_P3V3_AUX_FLT ; 2 = GND
PC8014  Q_CAP  22UF 16V 20% X6S  pkg C0805  page 190 : 1 = SW_P3V3_AUX_FLT ; 2 = GND
PC8071  Q_CAP  22UF 16V 20% X6S  pkg C0805  page 190 : 1 = SW_P3V3_AUX_FLT ; 2 = GND
PC8567  Q_CAP  22UF 16V 20% X6S  pkg C0805  page 190 : 1 = SW_P3V3_AUX_FLT ; 2 = GND
PD13  ZENER_AC  5.0SMDJ14A IC  pkg D2723_SMCXC  page 268 : A = GND ; C = P12V_PSU_FUSE
PD15  ZENER_AC  5.0SMDJ14A IC  pkg D2723_SMCXC  page 268 : A = GND ; C = P12V_PSU_FUSE

PD17  SS15P3SM386A  SS15P3S-M3/86A IC  pkg TO277A_4-3X6-1  page 266
  1  ANODE_1  IN  = GND
  2  ANODE_2  IN  = GND
  K  CATHODE  OUT  = P12V_AUX

PD101  DIODE_TVS  SMF14A IC  pkg SOD123F  page 134 : A = GND ; C = P12V_AUX
PD102  SCHOTTKY_AC  B340A-13-F IC  pkg D2010XF  page 134 : A = GND ; C = P12V_OCP_SFF
PD103  SCHOTTKY_AC  B340A-13-F IC  pkg D2010XF  page 134 : A = GND ; C = P3V3_OCP_SFF_R
PD107  DIODE_TVS  SMF14A IC  pkg SOD123F  page 140 : A = GND ; C = P12V_AUX
PD108  SCHOTTKY_AC  B340A-13-F IC  pkg D2010XF  page 140 : A = GND ; C = P12V_OCP_V3_2
PD109  SCHOTTKY_AC  B340A-13-F IC  pkg D2010XF  page 140 : A = GND ; C = P3V3_OCP_V3_2_R

PD111  SS15P3SM386A  SS15P3S-M3/86A IC  pkg TO277A_4-3X6-1  page 262
  1  ANODE_1  IN  = GND
  2  ANODE_2  IN  = GND
  K  CATHODE  OUT  = P12V_AUX

PD112  SCHOTTKY_AC  B340A-13-F IC  pkg D2010XF  page 146 : A = GND ; C = P12V_E1S_0
PD113  SCHOTTKY_AC  B340A-13-F IC  pkg D2010XF  page 146 : A = GND ; C = P3V3_E1S_0_R
PD114  DIODE_TVS  SMF14A IC  pkg SOD123F  page 146 : A = GND ; C = P12V_AUX
PD115  DIODE_TVS  SMF14A IC  pkg SOD123F  page 152 : A = GND ; C = P12V_AUX
PD116  SCHOTTKY_AC  B340A-13-F IC  pkg D2010XF  page 152 : A = GND ; C = P12V_SCM_R

PJ1  CONN3_210HP1030BR1  CONN3_210-HP1-030BR1 IO  pkg HEADER1X3XG  page 193
  1  \1\  BI  = GND
  2  \2\  BI  = SMB_SCM_2_R3_SDA
  3  \3\  BI  = SMB_SCM_2_R3_SCL

PJ09_P0_N  Q_SHORT  EMPTY  pkg SM  page 362 : 1 = GND ; 2 = P0V9_RETIMER_CPU0_SENSE_SH_N
PJ09_P0_P  Q_SHORT  EMPTY  pkg SM  page 362 : 1 = P0V9_CPU0_RT_2D ; 2 = P0V9_RETIMER_CPU0_SENSE_SH_P
PJ09_P1_N  Q_SHORT  EMPTY  pkg SM  page 364 : 1 = GND ; 2 = P0V9_RETIMER_CPU1_SENSE_SH_N
PJ09_P1_P  Q_SHORT  EMPTY  pkg SM  page 364 : 1 = P0V9_CPU1_RT_2D ; 2 = P0V9_RETIMER_CPU1_SENSE_SH_P

PJ38  SCONN21_9193031121LF  SCONN21_91930-31121LF IO  pkg CON_F21S2H2D2S_P1W4-22_LDH  page 267
  1  \1\  BI  = P12V_PSU
  2  \2\  BI  = P12V_HSC_SENSE1_P
  3  \3\  BI  = P12V_HSC_SENSE1_N
  4  \4\  BI  = P12V_HSC_SENSE2_P
  5  \5\  BI  = P12V_HSC_SENSE2_N
  6  \6\  BI  = P12V_HSC_ADC_N
  7  \7\  BI  = P12V_HSC_ADC_P
  8  \8\  BI  = P12V_HSC_GATE1
  9  \9\  BI  = P12V_HSC_GATE2
  10  \10\  BI  = P12V_AUX
  11  \11\  BI  = GND
  12  \12\  BI  = P3V3_AUX
  13  \13\  BI  = IRQ_HSC_FAULT_N
  14  \14\  BI  = HSC_EN
  15  \15\  BI  = MB0_P12V_STBY_PWRGD
  16  \16\  BI  = HSC_CSOUT
  17  \17\  BI  = HSC_TYPE_ADC
  18  \18\  BI  = SMB_SML1_PMBUS_HSC_R1_SCL
  19  \19\  BI  = SMB_SML1_PMBUS_HSC_R1_SDA
  20  \20\  BI  = IRQ_SML1_PMBUS_ALERT_N
  21  \21\  BI  = GND
  G1  G1  POWER  = GND
  G2  G2  POWER  = GND

PL7  Q_INDUCTOR4P_14  150NH IND  pkg L_TLM117513Q-151QL_11X7-5XA  page 203
  1  \1\  BI  = SW_PVDDCR_CPU1_P0_SW6
  2  \2\  BI  = IND_CPU1_P0_CPL0
  3  \3\  BI  = IND_CPU1_P0_CPL6
  4  \4\  BI  = PVDDCR_CPU1_P0

PL8  Q_INDUCTOR4P_14  150NH IND  pkg L_TLM117513Q-151QL_11X7-5XA  page 213
  1  \1\  BI  = SW_PVDDCR_CPU0_P1_SW6
  2  \2\  BI  = IND_CPU0_P1_CPL0
  3  \3\  BI  = IND_CPU0_P1_CPL6
  4  \4\  BI  = PVDDCR_CPU0_P1

PL9  Q_INDUCTOR  120NH/69A IND  pkg SMLF  page 203 : 1 = IND_CPU1_P0_CPL0 ; 2 = GND
